# T6G (Grand Teton) — schematic netlist excerpt (pin names and nets, part order shuffled) for the footprints in the layout excerpt that follows; sources: Cadence DE-HDL packaged netlist, KiCad conversion of 04192023_DAF0TMB3IC0_F0TG_MB_C_brd_V02_OCP.brd

PU6512  ISL99390FRZTR5935  ISL99390FRZ-TR5935 IC  pkg QFN21_6X5XB  page 365
  VOS  = P0V9_RETIMER_CPU1_VOS2
  AGND  = GND
  VCC  = P0V9_RETIMER_CPU1_VCC2
  PVCC  = P0V9_RETIMER_CPU1_PVCC
  PGND1  = GND
  GL1  = NC_PV09_RETIMER_CPU1_GL1_2
  PGND2  = GND
  SW  = SW_P0V9_RETIMER_CPU1_SW2
  VIN1  = SW_P12V_AUX_P0V9_RETIMER_CPU1_FLT
  VIN2  = SW_P12V_AUX_P0V9_RETIMER_CPU1_FLT
  DNC  = NC_PV09_RETIMER_CPU1_DNC2
  PHASE  = SW_P0V9_RETIMER_CPU1_PH2
  BOOT  = SW_P0V9_RETIMER_CPU1_BOOT2
  PWM  = P0V9_RETIMER_CPU1_PWM2
  EN  = P0V9_RETIMER_CPU1_VCC2
  TOUT_FLT  = P0V9_RETIMER_CPU1_TEMP0
  LSET  = P0V9_RETIMER_CPU1_LSET2
  IOUT  = P0V9_RETIMER_CPU1_IMON2
  REFIN  = PV09_RETIMER_CPU1_VCCS
  PGND3  = GND
  GL2  = NC_PV09_RETIMER_CPU1_GL2_2

(kicad_pcb
	(version 20260206)
	(generator "pcbnew")
	(generator_version "10.0")
	(general
		(thickness 1.6)
		(legacy_teardrops no)
	)
	(paper "A4")
	(title_block
		(title "04192023_DAF0TMB3IC0_F0TG_MB_C_brd_V02_OCP.brd")
		(comment 1 "Grand Teton / footprint 1600 of 8354 (PU6512), pads 1-21 of 21")
	)
	(layers
		(0 "F.Cu" signal "TOP")
		(4 "In1.Cu" signal "GND")
		(6 "In2.Cu" signal "IN1")
		(8 "In3.Cu" signal "GND1")
		(10 "In4.Cu" signal "IN2")
		(12 "In5.Cu" signal "GND2")
		(14 "In6.Cu" signal "IN3")
		(16 "In7.Cu" signal "GND3")
		(18 "In8.Cu" signal "VCC")
		(20 "In9.Cu" signal "VCC1")
		(22 "In10.Cu" signal "GND4")
		(24 "In11.Cu" signal "IN4")
		(26 "In12.Cu" signal "GND5")
		(28 "In13.Cu" signal "IN5")
		(30 "In14.Cu" signal "GND6")
		(32 "In15.Cu" signal "IN6")
		(34 "In16.Cu" signal "GND7")
		(2 "B.Cu" signal "BOTTOM")
		(9 "F.Adhes" user "F.Adhesive")
		(11 "B.Adhes" user "B.Adhesive")
		(13 "F.Paste" user "Package Geometry/Pastemask Top")
		(15 "B.Paste" user "Package Geometry/Pastemask Bottom")
		(5 "F.SilkS" user "Ref Des/Silkscreen Top")
		(7 "B.SilkS" user "Ref Des/Silkscreen Bottom")
		(1 "F.Mask" user "Board Geometry/Soldermask Top")
		(3 "B.Mask" user "Board Geometry/Soldermask Bottom")
		(17 "Dwgs.User" user "User.Drawings")
		(19 "Cmts.User" user "User.Comments")
		(21 "Eco1.User" user "User.Eco1")
		(23 "Eco2.User" user "User.Eco2")
		(25 "Edge.Cuts" user "Board Geometry/Outline")
		(27 "Margin" user)
		(31 "F.CrtYd" user "Package Geometry/Place Bound Top")
		(29 "B.CrtYd" user "Package Geometry/Place Bound Bottom")
		(35 "F.Fab" user "Ref Des/Assembly Top")
		(33 "B.Fab" user "Ref Des/Assembly Bottom")
	)
	(footprint ""
		(layer "F.Cu")
		(at 25.640792 -388.854188)
		(property "Reference" "PU6512"
			(at 2.525014 -4.833874 0)
			(unlocked yes)
			(layer "F.SilkS")
			(effects
				(font
					(size 0.7874 0.5842)
					(thickness 0.1524)
				)
				(justify left)
			)
		)
		(property "Value" ""
			(at 0 0 0)
			(layer "F.Fab")
			(effects
				(font
					(size 1.27 1.27)
				)
			)
		)
		(duplicate_pad_numbers_are_jumpers no)
		(pad "1" smd rect
			(at -2.400046 -2.275078 90)
			(size 0.2286 0.6096)
			(layers "F.Cu" "F.Mask" "F.Paste")
			(net "P0V9_RETIMER_CPU1_VOS2")
		)
		(pad "2" smd rect
			(at -2.400046 -1.82499 90)
			(size 0.2286 0.6096)
			(layers "F.Cu" "F.Mask" "F.Paste")
			(net "GND")
		)
		(pad "3" smd rect
			(at -2.400046 -1.374902 90)
			(size 0.2286 0.6096)
			(layers "F.Cu" "F.Mask" "F.Paste")
			(net "P0V9_RETIMER_CPU1_VCC2")
		)
		(pad "4" smd rect
			(at -2.400046 -0.925068 90)
			(size 0.2286 0.6096)
			(layers "F.Cu" "F.Mask" "F.Paste")
			(net "P0V9_RETIMER_CPU1_PVCC")
		)
		(pad "5" smd rect
			(at -2.400046 -0.47498 90)
			(size 0.2286 0.6096)
			(layers "F.Cu" "F.Mask" "F.Paste")
			(net "GND")
		)
		(pad "6" smd rect
			(at -2.400046 -0.024892 90)
			(size 0.2286 0.6096)
			(layers "F.Cu" "F.Mask" "F.Paste")
			(net "NC_PV09_RETIMER_CPU1_GL1_2")
		)
		(pad "7_9-20_24" smd circle
			(at 0 1.150112 90)
			(size 0 0)
			(layers "F.Cu" "F.Mask" "F.Paste")
			(net "GND")
		)
		(pad "10_19" smd rect
			(at 0 2.899918 90)
			(size 0.6096 4.318)
			(layers "F.Cu" "F.Mask" "F.Paste")
			(net "SW_P0V9_RETIMER_CPU1_SW2")
		)
		(pad "25_29" smd rect
			(at 1.549908 -1.279906 270)
			(size 2.0574 2.3114)
			(layers "F.Cu" "F.Mask" "F.Paste")
			(net "SW_P12V_AUX_P0V9_RETIMER_CPU1_FLT")
		)
		(pad "30" smd rect
			(at 2.05994 -2.899918)
			(size 0.2286 0.6096)
			(layers "F.Cu" "F.Mask" "F.Paste")
			(net "SW_P12V_AUX_P0V9_RETIMER_CPU1_FLT")
		)
		(pad "31" smd rect
			(at 1.610106 -2.899918)
			(size 0.2286 0.6096)
			(layers "F.Cu" "F.Mask" "F.Paste")
			(net "NC_PV09_RETIMER_CPU1_DNC2")
		)
		(pad "32" smd rect
			(at 1.160018 -2.899918)
			(size 0.2286 0.6096)
			(layers "F.Cu" "F.Mask" "F.Paste")
			(net "SW_P0V9_RETIMER_CPU1_PH2")
		)
		(pad "33" smd rect
			(at 0.70993 -2.899918)
			(size 0.2286 0.6096)
			(layers "F.Cu" "F.Mask" "F.Paste")
			(net "SW_P0V9_RETIMER_CPU1_BOOT2")
		)
		(pad "34" smd rect
			(at 0.260096 -2.899918)
			(size 0.2286 0.6096)
			(layers "F.Cu" "F.Mask" "F.Paste")
			(net "P0V9_RETIMER_CPU1_PWM2")
		)
		(pad "35" smd rect
			(at -0.189992 -2.899918)
			(size 0.2286 0.6096)
			(layers "F.Cu" "F.Mask" "F.Paste")
			(net "P0V9_RETIMER_CPU1_VCC2")
		)
		(pad "36" smd rect
			(at -0.64008 -2.899918)
			(size 0.2286 0.6096)
			(layers "F.Cu" "F.Mask" "F.Paste")
			(net "P0V9_RETIMER_CPU1_TEMP0")
		)
		(pad "37" smd rect
			(at -1.089914 -2.899918)
			(size 0.2286 0.6096)
			(layers "F.Cu" "F.Mask" "F.Paste")
			(net "P0V9_RETIMER_CPU1_LSET2")
		)
		(pad "38" smd rect
			(at -1.540002 -2.899918)
			(size 0.2286 0.6096)
			(layers "F.Cu" "F.Mask" "F.Paste")
			(net "P0V9_RETIMER_CPU1_IMON2")
		)
		(pad "39" smd rect
			(at -1.99009 -2.899918)
			(size 0.2286 0.6096)
			(layers "F.Cu" "F.Mask" "F.Paste")
			(net "PV09_RETIMER_CPU1_VCCS")
		)
		(pad "40" smd rect
			(at -0.87503 -1.27508)
			(size 1.7526 1.9558)
			(layers "F.Cu" "F.Mask" "F.Paste")
			(net "GND")
		)
		(pad "41" smd rect
			(at -1.525016 0.249936 270)
			(size 0.3048 0.4572)
			(layers "F.Cu" "F.Mask" "F.Paste")
			(net "NC_PV09_RETIMER_CPU1_GL2_2")
		)
	)
)
